(kicad_pcb
	(version 20260206)
	(generator "pcbnew")
	(generator_version "10.0")
	(general
		(thickness 1.6)
		(legacy_teardrops no)
	)
	(paper "A4")
	(title_block
		(title "Wiwynn_Tioga_Pass_MB.brd")
		(comment 1 "Tioga Pass / footprints 4474-4480 of 4770")
	)
	(layers
		(0 "F.Cu" signal "TOP")
		(4 "In1.Cu" signal "L2GND")
		(6 "In2.Cu" signal "L3")
		(8 "In3.Cu" signal "L4GND")
		(10 "In4.Cu" signal "L5")
		(12 "In5.Cu" signal "L6GND")
		(14 "In6.Cu" signal "L7VCC")
		(16 "In7.Cu" signal "L8VCC")
		(18 "In8.Cu" signal "L9GND")
		(20 "In9.Cu" signal "L10")
		(22 "In10.Cu" signal "L11GND")
		(24 "In11.Cu" signal "L12")
		(26 "In12.Cu" signal "L13GND")
		(2 "B.Cu" signal "BOTTOM")
		(9 "F.Adhes" user "F.Adhesive")
		(11 "B.Adhes" user "B.Adhesive")
		(13 "F.Paste" user "Package Geometry/Pastemask Top")
		(15 "B.Paste" user "Package Geometry/Pastemask Bottom")
		(5 "F.SilkS" user "Ref Des/Silkscreen Top")
		(7 "B.SilkS" user "Ref Des/Silkscreen Bottom")
		(1 "F.Mask" user "Board Geometry/Soldermask Top")
		(3 "B.Mask" user "Board Geometry/Soldermask Bottom")
		(17 "Dwgs.User" user "User.Drawings")
		(19 "Cmts.User" user "User.Comments")
		(21 "Eco1.User" user "User.Eco1")
		(23 "Eco2.User" user "User.Eco2")
		(25 "Edge.Cuts" user "Board Geometry/Outline")
		(27 "Margin" user)
		(31 "F.CrtYd" user "Package Geometry/Place Bound Top")
		(29 "B.CrtYd" user "Package Geometry/Place Bound Bottom")
		(35 "F.Fab" user "Ref Des/Assembly Top")
		(33 "B.Fab" user "Ref Des/Assembly Bottom")
	)
	(footprint ""
		(layer "B.Cu")
		(at 85.547708 -125.99162 -90)
		(property "Reference" "SH7L2"
			(at 0 0 90)
			(layer "B.SilkS")
			(hide yes)
			(effects
				(font
					(size 1.27 1.27)
				)
				(justify mirror)
			)
		)
		(property "Value" ""
			(at 0 0 90)
			(layer "B.Fab")
			(effects
				(font
					(size 1.27 1.27)
				)
				(justify mirror)
			)
		)
		(duplicate_pad_numbers_are_jumpers no)
		(fp_poly
			(pts
				(xy 0.1651 -0.0508) (xy 0.1651 0.5842) (xy -0.1651 0.5842) (xy -0.1651 -0.0508)
			)
			(stroke
				(width 0)
				(type default)
			)
			(fill no)
			(layer "B.CrtYd")
		)
		(fp_line
			(start -0.1651 0.5842)
			(end 0.1651 0.5842)
			(stroke
				(width 0.1)
				(type default)
			)
			(layer "B.Fab")
		)
		(fp_line
			(start 0.1651 0.5842)
			(end 0.1651 -0.0508)
			(stroke
				(width 0.1)
				(type default)
			)
			(layer "B.Fab")
		)
		(fp_line
			(start -0.1651 -0.0508)
			(end -0.1651 0.5842)
			(stroke
				(width 0.1)
				(type default)
			)
			(layer "B.Fab")
		)
		(fp_line
			(start 0.1651 -0.0508)
			(end -0.1651 -0.0508)
			(stroke
				(width 0.1)
				(type default)
			)
			(layer "B.Fab")
		)
		(pad "1" smd custom
			(at 0 0 270)
			(size 0.0762 0.0762)
			(layers "B.Cu" "B.Mask" "B.Paste")
			(net "VSENSE_PVDDQ_KLM_P")
			(options
				(clearance outline)
				(anchor circle)
			)
			(primitives
				(gr_poly
					(pts
						(arc
							(start -0.1524 0.10795)
							(mid -0.098518 0.130268)
							(end -0.0762 0.18415)
						)
						(xy -0.0762 0.22225) (xy 0.0762 0.22225)
						(arc
							(start 0.0762 0.18415)
							(mid 0.098518 0.130268)
							(end 0.1524 0.10795)
						)
						(xy 0.1524 -0.22225) (xy -0.1524 -0.22225)
					)
					(width 0)
					(fill yes)
				)
			)
		)
		(pad "2" smd custom
			(at 0 0.5334 90)
			(size 0.0762 0.0762)
			(layers "B.Cu" "B.Mask" "B.Paste")
			(net "PVDDQ_KLM")
			(options
				(clearance outline)
				(anchor circle)
			)
			(primitives
				(gr_poly
					(pts
						(arc
							(start -0.1524 0.10795)
							(mid -0.098518 0.130268)
							(end -0.0762 0.18415)
						)
						(xy -0.0762 0.22225) (xy 0.0762 0.22225)
						(arc
							(start 0.0762 0.18415)
							(mid 0.098518 0.130268)
							(end 0.1524 0.10795)
						)
						(xy 0.1524 -0.22225) (xy -0.1524 -0.22225)
					)
					(width 0)
					(fill yes)
				)
			)
		)
	)
	(footprint ""
		(layer "B.Cu")
		(at 445.72555 -29.6164)
		(property "Reference" "R1T29"
			(at 0 0 0)
			(layer "B.SilkS")
			(hide yes)
			(effects
				(font
					(size 1.27 1.27)
				)
				(justify mirror)
			)
		)
		(property "Value" ""
			(at 0 0 0)
			(layer "B.Fab")
			(effects
				(font
					(size 1.27 1.27)
				)
				(justify mirror)
			)
		)
		(duplicate_pad_numbers_are_jumpers no)
		(fp_poly
			(pts
				(xy 0.2794 -0.1016) (xy -0.2794 -0.1016) (xy -0.2794 0.9906) (xy 0.2794 0.9906)
			)
			(stroke
				(width 0)
				(type default)
			)
			(fill no)
			(layer "B.CrtYd")
		)
		(fp_line
			(start -0.2794 -0.1016)
			(end 0.2794 -0.1016)
			(stroke
				(width 0.1)
				(type default)
			)
			(layer "B.Fab")
		)
		(fp_line
			(start -0.2794 0.9906)
			(end -0.2794 -0.1016)
			(stroke
				(width 0.1)
				(type default)
			)
			(layer "B.Fab")
		)
		(fp_line
			(start 0.2794 -0.1016)
			(end 0.2794 0.9906)
			(stroke
				(width 0.1)
				(type default)
			)
			(layer "B.Fab")
		)
		(fp_line
			(start 0.2794 0.9906)
			(end -0.2794 0.9906)
			(stroke
				(width 0.1)
				(type default)
			)
			(layer "B.Fab")
		)
		(pad "1" smd rect
			(at 0 0 180)
			(size 0.508 0.508)
			(layers "B.Cu" "B.Mask" "B.Paste")
			(net "BMC_M_VREFCA")
		)
		(pad "2" smd rect
			(at 0 0.889 180)
			(size 0.508 0.508)
			(layers "B.Cu" "B.Mask" "B.Paste")
			(net "GND")
		)
		(zone
			(layer "B.Cu")
			(hatch none 0.5)
			(connect_pads
				(clearance 0)
			)
			(min_thickness 0.25)
			(keepout
				(tracks allowed)
				(vias not_allowed)
				(pads allowed)
				(copperpour not_allowed)
				(footprints allowed)
			)
			(placement
				(enabled no)
				(sheetname "")
			)
			(fill
				(thermal_gap 0.5)
				(thermal_bridge_width 0.5)
				(island_removal_mode 0)
			)
			(polygon
				(pts
					(xy 445.97955 -29.3624) (xy 445.47155 -29.3624) (xy 445.47155 -28.9814) (xy 445.97955 -28.9814)
				)
			)
		)
		(zone
			(layer "B.Cu")
			(hatch none 0.5)
			(connect_pads
				(clearance 0)
			)
			(min_thickness 0.25)
			(keepout
				(tracks not_allowed)
				(vias allowed)
				(pads allowed)
				(copperpour not_allowed)
				(footprints allowed)
			)
			(placement
				(enabled no)
				(sheetname "")
			)
			(fill
				(thermal_gap 0.5)
				(thermal_bridge_width 0.5)
				(island_removal_mode 0)
			)
			(polygon
				(pts
					(xy 445.97955 -28.9814) (xy 445.47155 -28.9814) (xy 445.47155 -29.3624) (xy 445.97955 -29.3624)
				)
			)
		)
	)
	(footprint ""
		(layer "B.Cu")
		(at 366.268 -40.5892 180)
		(property "Reference" "C8F5"
			(at 0 0 0)
			(layer "B.SilkS")
			(hide yes)
			(effects
				(font
					(size 1.27 1.27)
				)
				(justify mirror)
			)
		)
		(property "Value" ""
			(at 0 0 0)
			(layer "B.Fab")
			(effects
				(font
					(size 1.27 1.27)
				)
				(justify mirror)
			)
		)
		(duplicate_pad_numbers_are_jumpers no)
		(fp_poly
			(pts
				(xy -0.3048 -0.1016) (xy -0.3048 0.9906) (xy 0.3048 0.9906) (xy 0.3048 -0.1016)
			)
			(stroke
				(width 0)
				(type default)
			)
			(fill no)
			(layer "B.CrtYd")
		)
		(fp_line
			(start 0.3048 0.9906)
			(end -0.3048 0.9906)
			(stroke
				(width 0.1)
				(type default)
			)
			(layer "B.Fab")
		)
		(fp_line
			(start 0.3048 -0.1016)
			(end 0.3048 0.9906)
			(stroke
				(width 0.1)
				(type default)
			)
			(layer "B.Fab")
		)
		(fp_line
			(start -0.3048 0.9906)
			(end -0.3048 -0.1016)
			(stroke
				(width 0.1)
				(type default)
			)
			(layer "B.Fab")
		)
		(fp_line
			(start -0.3048 -0.1016)
			(end 0.3048 -0.1016)
			(stroke
				(width 0.1)
				(type default)
			)
			(layer "B.Fab")
		)
		(pad "1" smd rect
			(at 0 0)
			(size 0.508 0.508)
			(layers "B.Cu" "B.Mask" "B.Paste")
			(net "P3V3_STBY")
		)
		(pad "2" smd rect
			(at 0 0.889)
			(size 0.508 0.508)
			(layers "B.Cu" "B.Mask" "B.Paste")
			(net "GND")
		)
		(zone
			(layer "B.Cu")
			(hatch none 0.5)
			(connect_pads
				(clearance 0)
			)
			(min_thickness 0.25)
			(keepout
				(tracks not_allowed)
				(vias allowed)
				(pads allowed)
				(copperpour not_allowed)
				(footprints allowed)
			)
			(placement
				(enabled no)
				(sheetname "")
			)
			(fill
				(thermal_gap 0.5)
				(thermal_bridge_width 0.5)
				(island_removal_mode 0)
			)
			(polygon
				(pts
					(xy 366.014 -41.2242) (xy 366.522 -41.2242) (xy 366.522 -40.8432) (xy 366.014 -40.8432)
				)
			)
		)
		(zone
			(layer "B.Cu")
			(hatch none 0.5)
			(connect_pads
				(clearance 0)
			)
			(min_thickness 0.25)
			(keepout
				(tracks allowed)
				(vias not_allowed)
				(pads allowed)
				(copperpour not_allowed)
				(footprints allowed)
			)
			(placement
				(enabled no)
				(sheetname "")
			)
			(fill
				(thermal_gap 0.5)
				(thermal_bridge_width 0.5)
				(island_removal_mode 0)
			)
			(polygon
				(pts
					(xy 366.014 -40.8432) (xy 366.522 -40.8432) (xy 366.522 -41.2242) (xy 366.014 -41.2242)
				)
			)
		)
	)
	(footprint ""
		(layer "B.Cu")
		(at 444.548006 -43.54195 180)
		(property "Reference" "R25W44"
			(at 0 0 0)
			(layer "B.SilkS")
			(hide yes)
			(effects
				(font
					(size 1.27 1.27)
				)
				(justify mirror)
			)
		)
		(property "Value" "*"
			(at -0.064008 -4.108196 180)
			(unlocked yes)
			(layer "B.Fab")
			(hide yes)
			(effects
				(font
					(size 1.27 1.016)
					(thickness 0.1524)
				)
				(justify mirror)
			)
		)
		(property "Device Type" "120R2F-GP_RCL_GP-120R2F-GP,64.A"
			(at -0.064008 -5.632196 180)
			(unlocked yes)
			(layer "B.Fab")
			(hide yes)
			(effects
				(font
					(size 1.27 1.016)
					(thickness 0.1524)
				)
				(justify mirror)
			)
		)
		(duplicate_pad_numbers_are_jumpers no)
		(fp_line
			(start 0.508 -0.9398)
			(end 0.508 0.9398)
			(stroke
				(width 0.1524)
				(type default)
			)
			(layer "B.SilkS")
		)
		(fp_line
			(start -0.508 -0.9398)
			(end 0.508 -0.9398)
			(stroke
				(width 0.1524)
				(type default)
			)
			(layer "B.SilkS")
		)
		(fp_rect
			(start 0.508 0.9398)
			(end -0.508 -0.9398)
			(stroke
				(width 0)
				(type default)
			)
			(fill no)
			(layer "B.CrtYd")
		)
		(fp_rect
			(start 0.508 0.9398)
			(end -0.508 -0.9398)
			(stroke
				(width 0)
				(type default)
			)
			(fill no)
			(layer "B.Fab")
		)
		(pad "1" smd custom
			(at 0 -0.4445)
			(size 0.1397 0.1397)
			(layers "B.Cu" "B.Mask" "B.Paste")
			(net "BMC_M_A6")
			(options
				(clearance outline)
				(anchor circle)
			)
			(primitives
				(gr_poly
					(pts
						(arc
							(start -0.1778 0.2794)
							(mid -0.249642 0.249642)
							(end -0.2794 0.1778)
						)
						(arc
							(start -0.2794 -0.1778)
							(mid -0.249642 -0.249642)
							(end -0.1778 -0.2794)
						)
						(arc
							(start 0.1778 -0.2794)
							(mid 0.249642 -0.249642)
							(end 0.2794 -0.1778)
						)
						(arc
							(start 0.2794 0.1778)
							(mid 0.249642 0.249642)
							(end 0.1778 0.2794)
						)
					)
					(width 0)
					(fill yes)
				)
			)
		)
		(pad "2" smd custom
			(at 0 0.4445)
			(size 0.1397 0.1397)
			(layers "B.Cu" "B.Mask" "B.Paste")
			(net "P1V2_AUX_BMC")
			(options
				(clearance outline)
				(anchor circle)
			)
			(primitives
				(gr_poly
					(pts
						(arc
							(start -0.1778 0.2794)
							(mid -0.249642 0.249642)
							(end -0.2794 0.1778)
						)
						(arc
							(start -0.2794 -0.1778)
							(mid -0.249642 -0.249642)
							(end -0.1778 -0.2794)
						)
						(arc
							(start 0.1778 -0.2794)
							(mid 0.249642 -0.249642)
							(end 0.2794 -0.1778)
						)
						(arc
							(start 0.2794 0.1778)
							(mid 0.249642 0.249642)
							(end 0.1778 0.2794)
						)
					)
					(width 0)
					(fill yes)
				)
			)
		)
	)
	(footprint ""
		(layer "B.Cu")
		(at 461.899 -146.304 90)
		(property "Reference" "C1L5"
			(at 0 0 90)
			(layer "B.SilkS")
			(hide yes)
			(effects
				(font
					(size 1.27 1.27)
				)
				(justify mirror)
			)
		)
		(property "Value" ""
			(at 0 0 90)
			(layer "B.Fab")
			(effects
				(font
					(size 1.27 1.27)
				)
				(justify mirror)
			)
		)
		(duplicate_pad_numbers_are_jumpers no)
		(fp_poly
			(pts
				(xy -0.3048 -0.1016) (xy -0.3048 0.9906) (xy 0.3048 0.9906) (xy 0.3048 -0.1016)
			)
			(stroke
				(width 0)
				(type default)
			)
			(fill no)
			(layer "B.CrtYd")
		)
		(fp_line
			(start 0.3048 -0.1016)
			(end 0.3048 0.9906)
			(stroke
				(width 0.1)
				(type default)
			)
			(layer "B.Fab")
		)
		(fp_line
			(start -0.3048 -0.1016)
			(end 0.3048 -0.1016)
			(stroke
				(width 0.1)
				(type default)
			)
			(layer "B.Fab")
		)
		(fp_line
			(start 0.3048 0.9906)
			(end -0.3048 0.9906)
			(stroke
				(width 0.1)
				(type default)
			)
			(layer "B.Fab")
		)
		(fp_line
			(start -0.3048 0.9906)
			(end -0.3048 -0.1016)
			(stroke
				(width 0.1)
				(type default)
			)
			(layer "B.Fab")
		)
		(pad "1" smd rect
			(at 0 0 270)
			(size 0.508 0.508)
			(layers "B.Cu" "B.Mask" "B.Paste")
			(net "P1V05_PCH_STBY")
		)
		(pad "2" smd rect
			(at 0 0.889 270)
			(size 0.508 0.508)
			(layers "B.Cu" "B.Mask" "B.Paste")
			(net "GND")
		)
		(zone
			(layer "B.Cu")
			(hatch none 0.5)
			(connect_pads
				(clearance 0)
			)
			(min_thickness 0.25)
			(keepout
				(tracks allowed)
				(vias not_allowed)
				(pads allowed)
				(copperpour not_allowed)
				(footprints allowed)
			)
			(placement
				(enabled no)
				(sheetname "")
			)
			(fill
				(thermal_gap 0.5)
				(thermal_bridge_width 0.5)
				(island_removal_mode 0)
			)
			(polygon
				(pts
					(xy 462.153 -146.558) (xy 462.153 -146.05) (xy 462.534 -146.05) (xy 462.534 -146.558)
				)
			)
		)
		(zone
			(layer "B.Cu")
			(hatch none 0.5)
			(connect_pads
				(clearance 0)
			)
			(min_thickness 0.25)
			(keepout
				(tracks not_allowed)
				(vias allowed)
				(pads allowed)
				(copperpour not_allowed)
				(footprints allowed)
			)
			(placement
				(enabled no)
				(sheetname "")
			)
			(fill
				(thermal_gap 0.5)
				(thermal_bridge_width 0.5)
				(island_removal_mode 0)
			)
			(polygon
				(pts
					(xy 462.534 -146.558) (xy 462.534 -146.05) (xy 462.153 -146.05) (xy 462.153 -146.558)
				)
			)
		)
	)
	(footprint ""
		(layer "B.Cu")
		(at 488.22864 -60.024772 90)
		(property "Reference" "R30W4"
			(at 0.8382 -0.67818 90)
			(unlocked yes)
			(layer "B.SilkS")
			(effects
				(font
					(size 0.4064 0.254)
					(thickness 0.1524)
				)
				(justify left mirror)
			)
		)
		(property "Value" ""
			(at 0 0 90)
			(layer "B.Fab")
			(effects
				(font
					(size 1.27 1.27)
				)
				(justify mirror)
			)
		)
		(duplicate_pad_numbers_are_jumpers no)
		(fp_poly
			(pts
				(xy 0.2794 -0.1016) (xy -0.2794 -0.1016) (xy -0.2794 0.9906) (xy 0.2794 0.9906)
			)
			(stroke
				(width 0)
				(type default)
			)
			(fill no)
			(layer "B.CrtYd")
		)
		(fp_line
			(start 0.2794 -0.1016)
			(end 0.2794 0.9906)
			(stroke
				(width 0.1)
				(type default)
			)
			(layer "B.Fab")
		)
		(fp_line
			(start -0.2794 -0.1016)
			(end 0.2794 -0.1016)
			(stroke
				(width 0.1)
				(type default)
			)
			(layer "B.Fab")
		)
		(fp_line
			(start 0.2794 0.9906)
			(end -0.2794 0.9906)
			(stroke
				(width 0.1)
				(type default)
			)
			(layer "B.Fab")
		)
		(fp_line
			(start -0.2794 0.9906)
			(end -0.2794 -0.1016)
			(stroke
				(width 0.1)
				(type default)
			)
			(layer "B.Fab")
		)
		(pad "1" smd rect
			(at 0 0 270)
			(size 0.508 0.508)
			(layers "B.Cu" "B.Mask" "B.Paste")
			(net "USB3_P01_C_TXP")
		)
		(pad "2" smd rect
			(at 0 0.889 270)
			(size 0.508 0.508)
			(layers "B.Cu" "B.Mask" "B.Paste")
			(net "USB3_P01_FB_TXP")
		)
		(zone
			(layer "B.Cu")
			(hatch none 0.5)
			(connect_pads
				(clearance 0)
			)
			(min_thickness 0.25)
			(keepout
				(tracks allowed)
				(vias not_allowed)
				(pads allowed)
				(copperpour not_allowed)
				(footprints allowed)
			)
			(placement
				(enabled no)
				(sheetname "")
			)
			(fill
				(thermal_gap 0.5)
				(thermal_bridge_width 0.5)
				(island_removal_mode 0)
			)
			(polygon
				(pts
					(xy 488.48264 -60.278772) (xy 488.48264 -59.770772) (xy 488.86364 -59.770772) (xy 488.86364 -60.278772)
				)
			)
		)
		(zone
			(layer "B.Cu")
			(hatch none 0.5)
			(connect_pads
				(clearance 0)
			)
			(min_thickness 0.25)
			(keepout
				(tracks not_allowed)
				(vias allowed)
				(pads allowed)
				(copperpour not_allowed)
				(footprints allowed)
			)
			(placement
				(enabled no)
				(sheetname "")
			)
			(fill
				(thermal_gap 0.5)
				(thermal_bridge_width 0.5)
				(island_removal_mode 0)
			)
			(polygon
				(pts
					(xy 488.86364 -60.278772) (xy 488.86364 -59.770772) (xy 488.48264 -59.770772) (xy 488.48264 -60.278772)
				)
			)
		)
	)
	(footprint ""
		(layer "B.Cu")
		(at 461.7466 -126.7714)
		(property "Reference" "C1M36"
			(at 0 0 0)
			(layer "B.SilkS")
			(hide yes)
			(effects
				(font
					(size 1.27 1.27)
				)
				(justify mirror)
			)
		)
		(property "Value" ""
			(at 0 0 0)
			(layer "B.Fab")
			(effects
				(font
					(size 1.27 1.27)
				)
				(justify mirror)
			)
		)
		(duplicate_pad_numbers_are_jumpers no)
		(fp_poly
			(pts
				(xy -0.3048 -0.1016) (xy -0.3048 0.9906) (xy 0.3048 0.9906) (xy 0.3048 -0.1016)
			)
			(stroke
				(width 0)
				(type default)
			)
			(fill no)
			(layer "B.CrtYd")
		)
		(fp_line
			(start -0.3048 -0.1016)
			(end 0.3048 -0.1016)
			(stroke
				(width 0.1)
				(type default)
			)
			(layer "B.Fab")
		)
		(fp_line
			(start -0.3048 0.9906)
			(end -0.3048 -0.1016)
			(stroke
				(width 0.1)
				(type default)
			)
			(layer "B.Fab")
		)
		(fp_line
			(start 0.3048 -0.1016)
			(end 0.3048 0.9906)
			(stroke
				(width 0.1)
				(type default)
			)
			(layer "B.Fab")
		)
		(fp_line
			(start 0.3048 0.9906)
			(end -0.3048 0.9906)
			(stroke
				(width 0.1)
				(type default)
			)
			(layer "B.Fab")
		)
		(pad "1" smd rect
			(at 0 0 180)
			(size 0.508 0.508)
			(layers "B.Cu" "B.Mask" "B.Paste")
			(net "P3V3_STBY")
		)
		(pad "2" smd rect
			(at 0 0.889 180)
			(size 0.508 0.508)
			(layers "B.Cu" "B.Mask" "B.Paste")
			(net "GND")
		)
		(zone
			(layer "B.Cu")
			(hatch none 0.5)
			(connect_pads
				(clearance 0)
			)
			(min_thickness 0.25)
			(keepout
				(tracks allowed)
				(vias not_allowed)
				(pads allowed)
				(copperpour not_allowed)
				(footprints allowed)
			)
			(placement
				(enabled no)
				(sheetname "")
			)
			(fill
				(thermal_gap 0.5)
				(thermal_bridge_width 0.5)
				(island_removal_mode 0)
			)
			(polygon
				(pts
					(xy 462.0006 -126.5174) (xy 461.4926 -126.5174) (xy 461.4926 -126.1364) (xy 462.0006 -126.1364)
				)
			)
		)
		(zone
			(layer "B.Cu")
			(hatch none 0.5)
			(connect_pads
				(clearance 0)
			)
			(min_thickness 0.25)
			(keepout
				(tracks not_allowed)
				(vias allowed)
				(pads allowed)
				(copperpour not_allowed)
				(footprints allowed)
			)
			(placement
				(enabled no)
				(sheetname "")
			)
			(fill
				(thermal_gap 0.5)
				(thermal_bridge_width 0.5)
				(island_removal_mode 0)
			)
			(polygon
				(pts
					(xy 462.0006 -126.1364) (xy 461.4926 -126.1364) (xy 461.4926 -126.5174) (xy 462.0006 -126.5174)
				)
			)
		)
	)
)
